(kicad_pcb
	(version 20260206)
	(generator "pcbnew")
	(generator_version "10.0")
	(general
		(thickness 1.6)
		(legacy_teardrops no)
	)
	(paper "A4")
	(title_block
		(title "01162023_DA0F0TEBIF0_F0T_Expander_BD_F_brd_V02_OCP.brd")
		(comment 1 "Grand Teton / footprints 2522-2528 of 9728")
	)
	(layers
		(0 "F.Cu" signal "TOP")
		(4 "In1.Cu" signal "GND")
		(6 "In2.Cu" signal "VCC")
		(8 "In3.Cu" signal "VCC1")
		(10 "In4.Cu" signal "GND1")
		(12 "In5.Cu" signal "IN1")
		(14 "In6.Cu" signal "GND2")
		(16 "In7.Cu" signal "IN2")
		(18 "In8.Cu" signal "GND3")
		(20 "In9.Cu" signal "IN3")
		(22 "In10.Cu" signal "GND4")
		(24 "In11.Cu" signal "IN4")
		(26 "In12.Cu" signal "GND5")
		(28 "In13.Cu" signal "IN5")
		(30 "In14.Cu" signal "GND6")
		(32 "In15.Cu" signal "IN6")
		(34 "In16.Cu" signal "GND7")
		(2 "B.Cu" signal "BOTTOM")
		(9 "F.Adhes" user "F.Adhesive")
		(11 "B.Adhes" user "B.Adhesive")
		(13 "F.Paste" user "Package Geometry/Pastemask Top")
		(15 "B.Paste" user "Package Geometry/Pastemask Bottom")
		(5 "F.SilkS" user "Ref Des/Silkscreen Top")
		(7 "B.SilkS" user "Ref Des/Silkscreen Bottom")
		(1 "F.Mask" user "Board Geometry/Soldermask Top")
		(3 "B.Mask" user "Board Geometry/Soldermask Bottom")
		(17 "Dwgs.User" user "User.Drawings")
		(19 "Cmts.User" user "User.Comments")
		(21 "Eco1.User" user "User.Eco1")
		(23 "Eco2.User" user "User.Eco2")
		(25 "Edge.Cuts" user "Board Geometry/Outline")
		(27 "Margin" user)
		(31 "F.CrtYd" user "Package Geometry/Place Bound Top")
		(29 "B.CrtYd" user "Package Geometry/Place Bound Bottom")
		(35 "F.Fab" user "Ref Des/Assembly Top")
		(33 "B.Fab" user "Ref Des/Assembly Bottom")
	)
	(footprint ""
		(layer "F.Cu")
		(at 287.056068 -32.848042 -90)
		(property "Reference" "R6090"
			(at 0 0 270)
			(layer "F.SilkS")
			(hide yes)
			(effects
				(font
					(size 1.27 1.27)
				)
			)
		)
		(property "Value" ""
			(at 0 0 270)
			(layer "F.Fab")
			(effects
				(font
					(size 1.27 1.27)
				)
			)
		)
		(duplicate_pad_numbers_are_jumpers no)
		(fp_line
			(start -0.7874 0.4064)
			(end -0.7874 -0.4064)
			(stroke
				(width 0.1524)
				(type default)
			)
			(layer "F.SilkS")
		)
		(fp_line
			(start 0.7874 0.4064)
			(end -0.7874 0.4064)
			(stroke
				(width 0.1524)
				(type default)
			)
			(layer "F.SilkS")
		)
		(fp_line
			(start -0.7874 -0.4064)
			(end 0.7874 -0.4064)
			(stroke
				(width 0.1524)
				(type default)
			)
			(layer "F.SilkS")
		)
		(fp_line
			(start 0.7874 -0.4064)
			(end 0.7874 0.4064)
			(stroke
				(width 0.1524)
				(type default)
			)
			(layer "F.SilkS")
		)
		(fp_line
			(start -0.67945 0.3048)
			(end -0.67945 -0.305054)
			(stroke
				(width 0.1)
				(type default)
			)
			(layer "F.Fab")
		)
		(fp_line
			(start -0.12065 0.3048)
			(end -0.67945 0.3048)
			(stroke
				(width 0.1)
				(type default)
			)
			(layer "F.Fab")
		)
		(fp_line
			(start 0.120396 0.3048)
			(end 0.120396 0.2794)
			(stroke
				(width 0.1)
				(type default)
			)
			(layer "F.Fab")
		)
		(fp_line
			(start 0.67945 0.3048)
			(end 0.120396 0.3048)
			(stroke
				(width 0.1)
				(type default)
			)
			(layer "F.Fab")
		)
		(fp_line
			(start -0.12065 0.2794)
			(end -0.12065 0.3048)
			(stroke
				(width 0.1)
				(type default)
			)
			(layer "F.Fab")
		)
		(fp_line
			(start 0.120396 0.2794)
			(end -0.12065 0.2794)
			(stroke
				(width 0.1)
				(type default)
			)
			(layer "F.Fab")
		)
		(fp_line
			(start -0.12065 -0.2794)
			(end 0.12065 -0.2794)
			(stroke
				(width 0.1)
				(type default)
			)
			(layer "F.Fab")
		)
		(fp_line
			(start 0.12065 -0.2794)
			(end 0.12065 -0.3048)
			(stroke
				(width 0.1)
				(type default)
			)
			(layer "F.Fab")
		)
		(fp_line
			(start 0.12065 -0.3048)
			(end 0.67945 -0.3048)
			(stroke
				(width 0.1)
				(type default)
			)
			(layer "F.Fab")
		)
		(fp_line
			(start 0.67945 -0.3048)
			(end 0.67945 0.3048)
			(stroke
				(width 0.1)
				(type default)
			)
			(layer "F.Fab")
		)
		(fp_line
			(start -0.67945 -0.305054)
			(end -0.12065 -0.305054)
			(stroke
				(width 0.1)
				(type default)
			)
			(layer "F.Fab")
		)
		(fp_line
			(start -0.12065 -0.305054)
			(end -0.12065 -0.2794)
			(stroke
				(width 0.1)
				(type default)
			)
			(layer "F.Fab")
		)
		(pad "1" smd circle
			(at -0.40005 0 270)
			(size 0 0)
			(layers "F.Cu" "F.Mask" "F.Paste")
			(net "SSD10_AUX_P3V3_EN_R")
		)
		(pad "2" smd circle
			(at 0.40005 0 270)
			(size 0 0)
			(layers "F.Cu" "F.Mask" "F.Paste")
			(net "P3V3_SSD10_CO_EN")
		)
	)
	(footprint ""
		(layer "F.Cu")
		(at 127.658114 -253.178564 180)
		(property "Reference" "PR7131"
			(at 0 0 180)
			(layer "F.SilkS")
			(hide yes)
			(effects
				(font
					(size 1.27 1.27)
				)
			)
		)
		(property "Value" ""
			(at 0 0 180)
			(layer "F.Fab")
			(effects
				(font
					(size 1.27 1.27)
				)
			)
		)
		(duplicate_pad_numbers_are_jumpers no)
		(fp_line
			(start 0.7874 0.4064)
			(end -0.7874 0.4064)
			(stroke
				(width 0.1524)
				(type default)
			)
			(layer "F.SilkS")
		)
		(fp_line
			(start 0.7874 -0.4064)
			(end 0.7874 0.4064)
			(stroke
				(width 0.1524)
				(type default)
			)
			(layer "F.SilkS")
		)
		(fp_line
			(start -0.7874 0.4064)
			(end -0.7874 -0.4064)
			(stroke
				(width 0.1524)
				(type default)
			)
			(layer "F.SilkS")
		)
		(fp_line
			(start -0.7874 -0.4064)
			(end 0.7874 -0.4064)
			(stroke
				(width 0.1524)
				(type default)
			)
			(layer "F.SilkS")
		)
		(fp_line
			(start 0.67945 0.3048)
			(end 0.120396 0.3048)
			(stroke
				(width 0.1)
				(type default)
			)
			(layer "F.Fab")
		)
		(fp_line
			(start 0.67945 -0.3048)
			(end 0.67945 0.3048)
			(stroke
				(width 0.1)
				(type default)
			)
			(layer "F.Fab")
		)
		(fp_line
			(start 0.12065 -0.2794)
			(end 0.12065 -0.3048)
			(stroke
				(width 0.1)
				(type default)
			)
			(layer "F.Fab")
		)
		(fp_line
			(start 0.12065 -0.3048)
			(end 0.67945 -0.3048)
			(stroke
				(width 0.1)
				(type default)
			)
			(layer "F.Fab")
		)
		(fp_line
			(start 0.120396 0.3048)
			(end 0.120396 0.2794)
			(stroke
				(width 0.1)
				(type default)
			)
			(layer "F.Fab")
		)
		(fp_line
			(start 0.120396 0.2794)
			(end -0.12065 0.2794)
			(stroke
				(width 0.1)
				(type default)
			)
			(layer "F.Fab")
		)
		(fp_line
			(start -0.12065 0.3048)
			(end -0.67945 0.3048)
			(stroke
				(width 0.1)
				(type default)
			)
			(layer "F.Fab")
		)
		(fp_line
			(start -0.12065 0.2794)
			(end -0.12065 0.3048)
			(stroke
				(width 0.1)
				(type default)
			)
			(layer "F.Fab")
		)
		(fp_line
			(start -0.12065 -0.2794)
			(end 0.12065 -0.2794)
			(stroke
				(width 0.1)
				(type default)
			)
			(layer "F.Fab")
		)
		(fp_line
			(start -0.12065 -0.305054)
			(end -0.12065 -0.2794)
			(stroke
				(width 0.1)
				(type default)
			)
			(layer "F.Fab")
		)
		(fp_line
			(start -0.67945 0.3048)
			(end -0.67945 -0.305054)
			(stroke
				(width 0.1)
				(type default)
			)
			(layer "F.Fab")
		)
		(fp_line
			(start -0.67945 -0.305054)
			(end -0.12065 -0.305054)
			(stroke
				(width 0.1)
				(type default)
			)
			(layer "F.Fab")
		)
		(pad "1" smd circle
			(at -0.40005 0 180)
			(size 0 0)
			(layers "F.Cu" "F.Mask" "F.Paste")
			(net "P3V3_AUX")
		)
		(pad "2" smd circle
			(at 0.40005 0 180)
			(size 0 0)
			(layers "F.Cu" "F.Mask" "F.Paste")
			(net "P0V8_PEX0_SMBALERT")
		)
	)
	(footprint ""
		(layer "F.Cu")
		(at 247.553988 -308.568852)
		(property "Reference" "PJ13"
			(at 0 0 0)
			(layer "F.SilkS")
			(hide yes)
			(effects
				(font
					(size 1.27 1.27)
				)
			)
		)
		(property "Value" ""
			(at 0 0 0)
			(layer "F.Fab")
			(effects
				(font
					(size 1.27 1.27)
				)
			)
		)
		(duplicate_pad_numbers_are_jumpers no)
		(pad "1" smd circle
			(at -0.40005 0 90)
			(size 0 0)
			(layers "F.Cu" "F.Mask" "F.Paste")
			(net "SH_P1V25_PEX2_FB_P")
		)
		(pad "2" smd rect
			(at 0.40005 0 180)
			(size 0.4572 0.508)
			(layers "F.Cu" "F.Mask" "F.Paste")
			(net "P1V25_PEX2")
		)
		(zone
			(layer "F.Cu")
			(hatch none 0.5)
			(connect_pads
				(clearance 0)
			)
			(min_thickness 0.25)
			(keepout
				(tracks allowed)
				(vias not_allowed)
				(pads allowed)
				(copperpour not_allowed)
				(footprints allowed)
			)
			(placement
				(enabled no)
				(sheetname "")
			)
			(fill
				(thermal_gap 0.5)
				(thermal_bridge_width 0.5)
				(island_removal_mode 0)
			)
			(polygon
				(pts
					(xy 246.868188 -308.264052) (xy 248.239788 -308.264052) (xy 248.239788 -308.873652) (xy 246.868188 -308.873652)
				)
			)
		)
	)
	(footprint ""
		(layer "F.Cu")
		(at 369.24742 -19.33956)
		(property "Reference" "C3958"
			(at 0 0 0)
			(layer "F.SilkS")
			(hide yes)
			(effects
				(font
					(size 1.27 1.27)
				)
			)
		)
		(property "Value" ""
			(at 0 0 0)
			(layer "F.Fab")
			(effects
				(font
					(size 1.27 1.27)
				)
			)
		)
		(duplicate_pad_numbers_are_jumpers no)
		(fp_line
			(start -0.7874 -0.4064)
			(end 0.7874 -0.4064)
			(stroke
				(width 0.1524)
				(type default)
			)
			(layer "F.SilkS")
		)
		(fp_line
			(start -0.7874 0.4064)
			(end -0.7874 -0.4064)
			(stroke
				(width 0.1524)
				(type default)
			)
			(layer "F.SilkS")
		)
		(fp_line
			(start 0.7874 -0.4064)
			(end 0.7874 0.4064)
			(stroke
				(width 0.1524)
				(type default)
			)
			(layer "F.SilkS")
		)
		(fp_line
			(start 0.7874 0.4064)
			(end -0.7874 0.4064)
			(stroke
				(width 0.1524)
				(type default)
			)
			(layer "F.SilkS")
		)
		(fp_line
			(start -0.67945 -0.305054)
			(end -0.12065 -0.305054)
			(stroke
				(width 0.1)
				(type default)
			)
			(layer "F.Fab")
		)
		(fp_line
			(start -0.67945 0.3048)
			(end -0.67945 -0.305054)
			(stroke
				(width 0.1)
				(type default)
			)
			(layer "F.Fab")
		)
		(fp_line
			(start -0.12065 -0.305054)
			(end -0.12065 -0.2794)
			(stroke
				(width 0.1)
				(type default)
			)
			(layer "F.Fab")
		)
		(fp_line
			(start -0.12065 -0.2794)
			(end 0.12065 -0.2794)
			(stroke
				(width 0.1)
				(type default)
			)
			(layer "F.Fab")
		)
		(fp_line
			(start -0.12065 0.2794)
			(end -0.12065 0.3048)
			(stroke
				(width 0.1)
				(type default)
			)
			(layer "F.Fab")
		)
		(fp_line
			(start -0.12065 0.3048)
			(end -0.67945 0.3048)
			(stroke
				(width 0.1)
				(type default)
			)
			(layer "F.Fab")
		)
		(fp_line
			(start 0.120396 0.2794)
			(end -0.12065 0.2794)
			(stroke
				(width 0.1)
				(type default)
			)
			(layer "F.Fab")
		)
		(fp_line
			(start 0.120396 0.3048)
			(end 0.120396 0.2794)
			(stroke
				(width 0.1)
				(type default)
			)
			(layer "F.Fab")
		)
		(fp_line
			(start 0.12065 -0.3048)
			(end 0.67945 -0.3048)
			(stroke
				(width 0.1)
				(type default)
			)
			(layer "F.Fab")
		)
		(fp_line
			(start 0.12065 -0.2794)
			(end 0.12065 -0.3048)
			(stroke
				(width 0.1)
				(type default)
			)
			(layer "F.Fab")
		)
		(fp_line
			(start 0.67945 -0.3048)
			(end 0.67945 0.3048)
			(stroke
				(width 0.1)
				(type default)
			)
			(layer "F.Fab")
		)
		(fp_line
			(start 0.67945 0.3048)
			(end 0.120396 0.3048)
			(stroke
				(width 0.1)
				(type default)
			)
			(layer "F.Fab")
		)
		(pad "1" smd circle
			(at -0.40005 0)
			(size 0 0)
			(layers "F.Cu" "F.Mask" "F.Paste")
			(net "P12V_SSD12")
		)
		(pad "2" smd circle
			(at 0.40005 0)
			(size 0 0)
			(layers "F.Cu" "F.Mask" "F.Paste")
			(net "GND")
		)
	)
	(footprint ""
		(layer "F.Cu")
		(at 300.059344 -86.132162)
		(property "Reference" "C198"
			(at 0 0 0)
			(layer "F.SilkS")
			(hide yes)
			(effects
				(font
					(size 1.27 1.27)
				)
			)
		)
		(property "Value" ""
			(at 0 0 0)
			(layer "F.Fab")
			(effects
				(font
					(size 1.27 1.27)
				)
			)
		)
		(duplicate_pad_numbers_are_jumpers no)
		(fp_line
			(start -0.7874 -0.4064)
			(end 0.7874 -0.4064)
			(stroke
				(width 0.1524)
				(type default)
			)
			(layer "F.SilkS")
		)
		(fp_line
			(start -0.7874 0.4064)
			(end -0.7874 -0.4064)
			(stroke
				(width 0.1524)
				(type default)
			)
			(layer "F.SilkS")
		)
		(fp_line
			(start 0.7874 -0.4064)
			(end 0.7874 0.4064)
			(stroke
				(width 0.1524)
				(type default)
			)
			(layer "F.SilkS")
		)
		(fp_line
			(start 0.7874 0.4064)
			(end -0.7874 0.4064)
			(stroke
				(width 0.1524)
				(type default)
			)
			(layer "F.SilkS")
		)
		(fp_line
			(start -0.67945 -0.305054)
			(end -0.12065 -0.305054)
			(stroke
				(width 0.1)
				(type default)
			)
			(layer "F.Fab")
		)
		(fp_line
			(start -0.67945 0.3048)
			(end -0.67945 -0.305054)
			(stroke
				(width 0.1)
				(type default)
			)
			(layer "F.Fab")
		)
		(fp_line
			(start -0.12065 -0.305054)
			(end -0.12065 -0.2794)
			(stroke
				(width 0.1)
				(type default)
			)
			(layer "F.Fab")
		)
		(fp_line
			(start -0.12065 -0.2794)
			(end 0.12065 -0.2794)
			(stroke
				(width 0.1)
				(type default)
			)
			(layer "F.Fab")
		)
		(fp_line
			(start -0.12065 0.2794)
			(end -0.12065 0.3048)
			(stroke
				(width 0.1)
				(type default)
			)
			(layer "F.Fab")
		)
		(fp_line
			(start -0.12065 0.3048)
			(end -0.67945 0.3048)
			(stroke
				(width 0.1)
				(type default)
			)
			(layer "F.Fab")
		)
		(fp_line
			(start 0.120396 0.2794)
			(end -0.12065 0.2794)
			(stroke
				(width 0.1)
				(type default)
			)
			(layer "F.Fab")
		)
		(fp_line
			(start 0.120396 0.3048)
			(end 0.120396 0.2794)
			(stroke
				(width 0.1)
				(type default)
			)
			(layer "F.Fab")
		)
		(fp_line
			(start 0.12065 -0.3048)
			(end 0.67945 -0.3048)
			(stroke
				(width 0.1)
				(type default)
			)
			(layer "F.Fab")
		)
		(fp_line
			(start 0.12065 -0.2794)
			(end 0.12065 -0.3048)
			(stroke
				(width 0.1)
				(type default)
			)
			(layer "F.Fab")
		)
		(fp_line
			(start 0.67945 -0.3048)
			(end 0.67945 0.3048)
			(stroke
				(width 0.1)
				(type default)
			)
			(layer "F.Fab")
		)
		(fp_line
			(start 0.67945 0.3048)
			(end 0.120396 0.3048)
			(stroke
				(width 0.1)
				(type default)
			)
			(layer "F.Fab")
		)
		(pad "1" smd circle
			(at -0.40005 0)
			(size 0 0)
			(layers "F.Cu" "F.Mask" "F.Paste")
			(net "P3V3_AUX")
		)
		(pad "2" smd circle
			(at 0.40005 0)
			(size 0 0)
			(layers "F.Cu" "F.Mask" "F.Paste")
			(net "GND")
		)
	)
	(footprint ""
		(layer "F.Cu")
		(at 145.734278 -387.660896)
		(property "Reference" "R6298"
			(at 0 0 0)
			(layer "F.SilkS")
			(hide yes)
			(effects
				(font
					(size 1.27 1.27)
				)
			)
		)
		(property "Value" ""
			(at 0 0 0)
			(layer "F.Fab")
			(effects
				(font
					(size 1.27 1.27)
				)
			)
		)
		(duplicate_pad_numbers_are_jumpers no)
		(fp_line
			(start -0.7874 -0.4064)
			(end 0.7874 -0.4064)
			(stroke
				(width 0.1524)
				(type default)
			)
			(layer "F.SilkS")
		)
		(fp_line
			(start -0.7874 0.4064)
			(end -0.7874 -0.4064)
			(stroke
				(width 0.1524)
				(type default)
			)
			(layer "F.SilkS")
		)
		(fp_line
			(start 0.7874 -0.4064)
			(end 0.7874 0.4064)
			(stroke
				(width 0.1524)
				(type default)
			)
			(layer "F.SilkS")
		)
		(fp_line
			(start 0.7874 0.4064)
			(end -0.7874 0.4064)
			(stroke
				(width 0.1524)
				(type default)
			)
			(layer "F.SilkS")
		)
		(fp_line
			(start -0.67945 -0.305054)
			(end -0.12065 -0.305054)
			(stroke
				(width 0.1)
				(type default)
			)
			(layer "F.Fab")
		)
		(fp_line
			(start -0.67945 0.3048)
			(end -0.67945 -0.305054)
			(stroke
				(width 0.1)
				(type default)
			)
			(layer "F.Fab")
		)
		(fp_line
			(start -0.12065 -0.305054)
			(end -0.12065 -0.2794)
			(stroke
				(width 0.1)
				(type default)
			)
			(layer "F.Fab")
		)
		(fp_line
			(start -0.12065 -0.2794)
			(end 0.12065 -0.2794)
			(stroke
				(width 0.1)
				(type default)
			)
			(layer "F.Fab")
		)
		(fp_line
			(start -0.12065 0.2794)
			(end -0.12065 0.3048)
			(stroke
				(width 0.1)
				(type default)
			)
			(layer "F.Fab")
		)
		(fp_line
			(start -0.12065 0.3048)
			(end -0.67945 0.3048)
			(stroke
				(width 0.1)
				(type default)
			)
			(layer "F.Fab")
		)
		(fp_line
			(start 0.120396 0.2794)
			(end -0.12065 0.2794)
			(stroke
				(width 0.1)
				(type default)
			)
			(layer "F.Fab")
		)
		(fp_line
			(start 0.120396 0.3048)
			(end 0.120396 0.2794)
			(stroke
				(width 0.1)
				(type default)
			)
			(layer "F.Fab")
		)
		(fp_line
			(start 0.12065 -0.3048)
			(end 0.67945 -0.3048)
			(stroke
				(width 0.1)
				(type default)
			)
			(layer "F.Fab")
		)
		(fp_line
			(start 0.12065 -0.2794)
			(end 0.12065 -0.3048)
			(stroke
				(width 0.1)
				(type default)
			)
			(layer "F.Fab")
		)
		(fp_line
			(start 0.67945 -0.3048)
			(end 0.67945 0.3048)
			(stroke
				(width 0.1)
				(type default)
			)
			(layer "F.Fab")
		)
		(fp_line
			(start 0.67945 0.3048)
			(end 0.120396 0.3048)
			(stroke
				(width 0.1)
				(type default)
			)
			(layer "F.Fab")
		)
		(pad "1" smd circle
			(at -0.40005 0)
			(size 0 0)
			(layers "F.Cu" "F.Mask" "F.Paste")
			(net "MB_BMC_MON")
		)
		(pad "2" smd circle
			(at 0.40005 0)
			(size 0 0)
			(layers "F.Cu" "F.Mask" "F.Paste")
			(net "GND")
		)
	)
	(footprint ""
		(layer "F.Cu")
		(at 6.521196 -378.533914 -90)
		(property "Reference" "R6737"
			(at 0 0 270)
			(layer "F.SilkS")
			(hide yes)
			(effects
				(font
					(size 1.27 1.27)
				)
			)
		)
		(property "Value" ""
			(at 0 0 270)
			(layer "F.Fab")
			(effects
				(font
					(size 1.27 1.27)
				)
			)
		)
		(duplicate_pad_numbers_are_jumpers no)
		(fp_line
			(start -0.7874 0.4064)
			(end -0.7874 -0.4064)
			(stroke
				(width 0.1524)
				(type default)
			)
			(layer "F.SilkS")
		)
		(fp_line
			(start 0.7874 0.4064)
			(end -0.7874 0.4064)
			(stroke
				(width 0.1524)
				(type default)
			)
			(layer "F.SilkS")
		)
		(fp_line
			(start -0.7874 -0.4064)
			(end 0.7874 -0.4064)
			(stroke
				(width 0.1524)
				(type default)
			)
			(layer "F.SilkS")
		)
		(fp_line
			(start 0.7874 -0.4064)
			(end 0.7874 0.4064)
			(stroke
				(width 0.1524)
				(type default)
			)
			(layer "F.SilkS")
		)
		(fp_line
			(start -0.67945 0.3048)
			(end -0.67945 -0.305054)
			(stroke
				(width 0.1)
				(type default)
			)
			(layer "F.Fab")
		)
		(fp_line
			(start -0.12065 0.3048)
			(end -0.67945 0.3048)
			(stroke
				(width 0.1)
				(type default)
			)
			(layer "F.Fab")
		)
		(fp_line
			(start 0.120396 0.3048)
			(end 0.120396 0.2794)
			(stroke
				(width 0.1)
				(type default)
			)
			(layer "F.Fab")
		)
		(fp_line
			(start 0.67945 0.3048)
			(end 0.120396 0.3048)
			(stroke
				(width 0.1)
				(type default)
			)
			(layer "F.Fab")
		)
		(fp_line
			(start -0.12065 0.2794)
			(end -0.12065 0.3048)
			(stroke
				(width 0.1)
				(type default)
			)
			(layer "F.Fab")
		)
		(fp_line
			(start 0.120396 0.2794)
			(end -0.12065 0.2794)
			(stroke
				(width 0.1)
				(type default)
			)
			(layer "F.Fab")
		)
		(fp_line
			(start -0.12065 -0.2794)
			(end 0.12065 -0.2794)
			(stroke
				(width 0.1)
				(type default)
			)
			(layer "F.Fab")
		)
		(fp_line
			(start 0.12065 -0.2794)
			(end 0.12065 -0.3048)
			(stroke
				(width 0.1)
				(type default)
			)
			(layer "F.Fab")
		)
		(fp_line
			(start 0.12065 -0.3048)
			(end 0.67945 -0.3048)
			(stroke
				(width 0.1)
				(type default)
			)
			(layer "F.Fab")
		)
		(fp_line
			(start 0.67945 -0.3048)
			(end 0.67945 0.3048)
			(stroke
				(width 0.1)
				(type default)
			)
			(layer "F.Fab")
		)
		(fp_line
			(start -0.67945 -0.305054)
			(end -0.12065 -0.305054)
			(stroke
				(width 0.1)
				(type default)
			)
			(layer "F.Fab")
		)
		(fp_line
			(start -0.12065 -0.305054)
			(end -0.12065 -0.2794)
			(stroke
				(width 0.1)
				(type default)
			)
			(layer "F.Fab")
		)
		(pad "1" smd circle
			(at -0.40005 0 270)
			(size 0 0)
			(layers "F.Cu" "F.Mask" "F.Paste")
			(net "BIC_USB_8042_HUB_R1")
		)
		(pad "2" smd circle
			(at 0.40005 0 270)
			(size 0 0)
			(layers "F.Cu" "F.Mask" "F.Paste")
			(net "GND")
		)
	)
)
